# T6G (Grand Teton) — schematic netlist excerpt (pin names and nets, part order shuffled) for the footprints in the layout excerpt that follows; sources: Cadence DE-HDL packaged netlist, KiCad conversion of 04192023_DAF0TMB3IC0_F0TG_MB_C_brd_V02_OCP.brd

R1707  Q_RES  10 1% CHIP  pkg 0402LF  page 105 : A = I3C_SPD_DDRGL_CPU1_SDA ; B = I3C_SPD_DDRH_CPU1_SDA
PC613_3  Q_CAP  22UF 16V 20% X6S  pkg C0805  page 199 : A = SW_P12V_AUX_PVDDCR_SOC_P0_FLT ; B = GND
C180  Q_CAP  0.1UF 25V 10% X7R  pkg 0402  page 109 : A = P3V3_AUX ; B = GND

(kicad_pcb
	(version 20260206)
	(generator "pcbnew")
	(generator_version "10.0")
	(general
		(thickness 1.6)
		(legacy_teardrops no)
	)
	(paper "A4")
	(title_block
		(title "04192023_DAF0TMB3IC0_F0TG_MB_C_brd_V02_OCP.brd")
		(comment 1 "Grand Teton / footprints 6818-6820 of 8354")
	)
	(layers
		(0 "F.Cu" signal "TOP")
		(4 "In1.Cu" signal "GND")
		(6 "In2.Cu" signal "IN1")
		(8 "In3.Cu" signal "GND1")
		(10 "In4.Cu" signal "IN2")
		(12 "In5.Cu" signal "GND2")
		(14 "In6.Cu" signal "IN3")
		(16 "In7.Cu" signal "GND3")
		(18 "In8.Cu" signal "VCC")
		(20 "In9.Cu" signal "VCC1")
		(22 "In10.Cu" signal "GND4")
		(24 "In11.Cu" signal "IN4")
		(26 "In12.Cu" signal "GND5")
		(28 "In13.Cu" signal "IN5")
		(30 "In14.Cu" signal "GND6")
		(32 "In15.Cu" signal "IN6")
		(34 "In16.Cu" signal "GND7")
		(2 "B.Cu" signal "BOTTOM")
		(9 "F.Adhes" user "F.Adhesive")
		(11 "B.Adhes" user "B.Adhesive")
		(13 "F.Paste" user "Package Geometry/Pastemask Top")
		(15 "B.Paste" user "Package Geometry/Pastemask Bottom")
		(5 "F.SilkS" user "Ref Des/Silkscreen Top")
		(7 "B.SilkS" user "Ref Des/Silkscreen Bottom")
		(1 "F.Mask" user "Board Geometry/Soldermask Top")
		(3 "B.Mask" user "Board Geometry/Soldermask Bottom")
		(17 "Dwgs.User" user "User.Drawings")
		(19 "Cmts.User" user "User.Comments")
		(21 "Eco1.User" user "User.Eco1")
		(23 "Eco2.User" user "User.Eco2")
		(25 "Edge.Cuts" user "Board Geometry/Outline")
		(27 "Margin" user)
		(31 "F.CrtYd" user "Package Geometry/Place Bound Top")
		(29 "B.CrtYd" user "Package Geometry/Place Bound Bottom")
		(35 "F.Fab" user "Ref Des/Assembly Top")
		(33 "B.Fab" user "Ref Des/Assembly Bottom")
	)
	(footprint ""
		(layer "B.Cu")
		(at 413.502856 -163.891468 -90)
		(property "Reference" "PC613_3"
			(at 0 0 90)
			(layer "B.SilkS")
			(hide yes)
			(effects
				(font
					(size 1.27 1.27)
				)
				(justify mirror)
			)
		)
		(property "Value" ""
			(at 0 0 90)
			(layer "B.Fab")
			(effects
				(font
					(size 1.27 1.27)
				)
				(justify mirror)
			)
		)
		(duplicate_pad_numbers_are_jumpers no)
		(fp_line
			(start -1.524 0.762)
			(end 1.524 0.762)
			(stroke
				(width 0.1524)
				(type default)
			)
			(layer "B.SilkS")
		)
		(fp_line
			(start 1.524 0.762)
			(end 1.524 -0.762)
			(stroke
				(width 0.1524)
				(type default)
			)
			(layer "B.SilkS")
		)
		(fp_line
			(start -1.524 -0.762)
			(end -1.524 0.762)
			(stroke
				(width 0.1524)
				(type default)
			)
			(layer "B.SilkS")
		)
		(fp_line
			(start 1.524 -0.762)
			(end -1.524 -0.762)
			(stroke
				(width 0.1524)
				(type default)
			)
			(layer "B.SilkS")
		)
		(fp_line
			(start -1.1049 0.724916)
			(end -1.1049 -0.724916)
			(stroke
				(width 0.1)
				(type default)
			)
			(layer "B.Fab")
		)
		(fp_line
			(start 1.1049 0.724916)
			(end -1.1049 0.724916)
			(stroke
				(width 0.1)
				(type default)
			)
			(layer "B.Fab")
		)
		(fp_line
			(start -1.1049 -0.724916)
			(end 1.1049 -0.724916)
			(stroke
				(width 0.1)
				(type default)
			)
			(layer "B.Fab")
		)
		(fp_line
			(start 1.1049 -0.724916)
			(end 1.1049 0.724916)
			(stroke
				(width 0.1)
				(type default)
			)
			(layer "B.Fab")
		)
		(pad "1" smd rect
			(at 0.889 0 270)
			(size 1.016 1.27)
			(layers "B.Cu" "B.Mask" "B.Paste")
			(net "SW_P12V_AUX_PVDDCR_SOC_P0_FLT")
		)
		(pad "2" smd rect
			(at -0.889 0 270)
			(size 1.016 1.27)
			(layers "B.Cu" "B.Mask" "B.Paste")
			(net "GND")
		)
	)
	(footprint ""
		(layer "B.Cu")
		(at 175.316642 -195.8594 180)
		(property "Reference" "R1707"
			(at 0 0 0)
			(layer "B.SilkS")
			(hide yes)
			(effects
				(font
					(size 1.27 1.27)
				)
				(justify mirror)
			)
		)
		(property "Value" ""
			(at 0 0 0)
			(layer "B.Fab")
			(effects
				(font
					(size 1.27 1.27)
				)
				(justify mirror)
			)
		)
		(duplicate_pad_numbers_are_jumpers no)
		(fp_line
			(start 0.7874 0.4064)
			(end 0.7874 -0.4064)
			(stroke
				(width 0.1524)
				(type default)
			)
			(layer "B.SilkS")
		)
		(fp_line
			(start 0.7874 -0.4064)
			(end -0.7874 -0.4064)
			(stroke
				(width 0.1524)
				(type default)
			)
			(layer "B.SilkS")
		)
		(fp_line
			(start -0.7874 0.4064)
			(end 0.7874 0.4064)
			(stroke
				(width 0.1524)
				(type default)
			)
			(layer "B.SilkS")
		)
		(fp_line
			(start -0.7874 -0.4064)
			(end -0.7874 0.4064)
			(stroke
				(width 0.1524)
				(type default)
			)
			(layer "B.SilkS")
		)
		(fp_line
			(start 0.67945 0.3048)
			(end 0.67945 -0.305054)
			(stroke
				(width 0.1)
				(type default)
			)
			(layer "B.Fab")
		)
		(fp_line
			(start 0.67945 -0.305054)
			(end 0.12065 -0.305054)
			(stroke
				(width 0.1)
				(type default)
			)
			(layer "B.Fab")
		)
		(fp_line
			(start 0.12065 0.3048)
			(end 0.67945 0.3048)
			(stroke
				(width 0.1)
				(type default)
			)
			(layer "B.Fab")
		)
		(fp_line
			(start 0.12065 0.2794)
			(end 0.12065 0.3048)
			(stroke
				(width 0.1)
				(type default)
			)
			(layer "B.Fab")
		)
		(fp_line
			(start 0.12065 -0.2794)
			(end -0.12065 -0.2794)
			(stroke
				(width 0.1)
				(type default)
			)
			(layer "B.Fab")
		)
		(fp_line
			(start 0.12065 -0.305054)
			(end 0.12065 -0.2794)
			(stroke
				(width 0.1)
				(type default)
			)
			(layer "B.Fab")
		)
		(fp_line
			(start -0.120396 0.3048)
			(end -0.120396 0.2794)
			(stroke
				(width 0.1)
				(type default)
			)
			(layer "B.Fab")
		)
		(fp_line
			(start -0.120396 0.2794)
			(end 0.12065 0.2794)
			(stroke
				(width 0.1)
				(type default)
			)
			(layer "B.Fab")
		)
		(fp_line
			(start -0.12065 -0.2794)
			(end -0.12065 -0.3048)
			(stroke
				(width 0.1)
				(type default)
			)
			(layer "B.Fab")
		)
		(fp_line
			(start -0.12065 -0.3048)
			(end -0.67945 -0.3048)
			(stroke
				(width 0.1)
				(type default)
			)
			(layer "B.Fab")
		)
		(fp_line
			(start -0.67945 0.3048)
			(end -0.120396 0.3048)
			(stroke
				(width 0.1)
				(type default)
			)
			(layer "B.Fab")
		)
		(fp_line
			(start -0.67945 -0.3048)
			(end -0.67945 0.3048)
			(stroke
				(width 0.1)
				(type default)
			)
			(layer "B.Fab")
		)
		(pad "1" smd circle
			(at 0.40005 0)
			(size 0 0)
			(layers "B.Cu" "B.Mask" "B.Paste")
			(net "I3C_SPD_DDRGL_CPU1_SDA")
		)
		(pad "2" smd circle
			(at -0.40005 0)
			(size 0 0)
			(layers "B.Cu" "B.Mask" "B.Paste")
			(net "I3C_SPD_DDRH_CPU1_SDA")
		)
	)
	(footprint ""
		(layer "B.Cu")
		(at 206.22133 -193.99631)
		(property "Reference" "C180"
			(at 0 0 0)
			(layer "B.SilkS")
			(hide yes)
			(effects
				(font
					(size 1.27 1.27)
				)
				(justify mirror)
			)
		)
		(property "Value" ""
			(at 0 0 0)
			(layer "B.Fab")
			(effects
				(font
					(size 1.27 1.27)
				)
				(justify mirror)
			)
		)
		(duplicate_pad_numbers_are_jumpers no)
		(fp_line
			(start -0.7874 -0.4064)
			(end -0.7874 0.4064)
			(stroke
				(width 0.1524)
				(type default)
			)
			(layer "B.SilkS")
		)
		(fp_line
			(start -0.7874 0.4064)
			(end 0.7874 0.4064)
			(stroke
				(width 0.1524)
				(type default)
			)
			(layer "B.SilkS")
		)
		(fp_line
			(start 0.7874 -0.4064)
			(end -0.7874 -0.4064)
			(stroke
				(width 0.1524)
				(type default)
			)
			(layer "B.SilkS")
		)
		(fp_line
			(start 0.7874 0.4064)
			(end 0.7874 -0.4064)
			(stroke
				(width 0.1524)
				(type default)
			)
			(layer "B.SilkS")
		)
		(fp_line
			(start -0.67945 -0.3048)
			(end -0.67945 0.3048)
			(stroke
				(width 0.1)
				(type default)
			)
			(layer "B.Fab")
		)
		(fp_line
			(start -0.67945 0.3048)
			(end -0.120396 0.3048)
			(stroke
				(width 0.1)
				(type default)
			)
			(layer "B.Fab")
		)
		(fp_line
			(start -0.12065 -0.3048)
			(end -0.67945 -0.3048)
			(stroke
				(width 0.1)
				(type default)
			)
			(layer "B.Fab")
		)
		(fp_line
			(start -0.12065 -0.2794)
			(end -0.12065 -0.3048)
			(stroke
				(width 0.1)
				(type default)
			)
			(layer "B.Fab")
		)
		(fp_line
			(start -0.120396 0.2794)
			(end 0.12065 0.2794)
			(stroke
				(width 0.1)
				(type default)
			)
			(layer "B.Fab")
		)
		(fp_line
			(start -0.120396 0.3048)
			(end -0.120396 0.2794)
			(stroke
				(width 0.1)
				(type default)
			)
			(layer "B.Fab")
		)
		(fp_line
			(start 0.12065 -0.305054)
			(end 0.12065 -0.2794)
			(stroke
				(width 0.1)
				(type default)
			)
			(layer "B.Fab")
		)
		(fp_line
			(start 0.12065 -0.2794)
			(end -0.12065 -0.2794)
			(stroke
				(width 0.1)
				(type default)
			)
			(layer "B.Fab")
		)
		(fp_line
			(start 0.12065 0.2794)
			(end 0.12065 0.3048)
			(stroke
				(width 0.1)
				(type default)
			)
			(layer "B.Fab")
		)
		(fp_line
			(start 0.12065 0.3048)
			(end 0.67945 0.3048)
			(stroke
				(width 0.1)
				(type default)
			)
			(layer "B.Fab")
		)
		(fp_line
			(start 0.67945 -0.305054)
			(end 0.12065 -0.305054)
			(stroke
				(width 0.1)
				(type default)
			)
			(layer "B.Fab")
		)
		(fp_line
			(start 0.67945 0.3048)
			(end 0.67945 -0.305054)
			(stroke
				(width 0.1)
				(type default)
			)
			(layer "B.Fab")
		)
		(pad "1" smd circle
			(at 0.40005 0 180)
			(size 0 0)
			(layers "B.Cu" "B.Mask" "B.Paste")
			(net "P3V3_AUX")
		)
		(pad "2" smd circle
			(at -0.40005 0 180)
			(size 0 0)
			(layers "B.Cu" "B.Mask" "B.Paste")
			(net "GND")
		)
	)
)
